(kicad_pcb
	(version 20260206)
	(generator "pcbnew")
	(generator_version "10.0")
	(general
		(thickness 1.6)
		(legacy_teardrops no)
	)
	(paper "A4")
	(title_block
		(title "4HDD Backplane_Layout.brd")
		(comment 1 "Tioga Pass / footprints 51-55 of 97")
	)
	(layers
		(0 "F.Cu" signal "TOP")
		(4 "In1.Cu" signal "L2GND")
		(6 "In2.Cu" signal "L3")
		(8 "In3.Cu" signal "L4")
		(10 "In4.Cu" signal "L5GND")
		(2 "B.Cu" signal "BOTTOM")
		(9 "F.Adhes" user "F.Adhesive")
		(11 "B.Adhes" user "B.Adhesive")
		(13 "F.Paste" user "Package Geometry/Pastemask Top")
		(15 "B.Paste" user "Package Geometry/Pastemask Bottom")
		(5 "F.SilkS" user "Ref Des/Silkscreen Top")
		(7 "B.SilkS" user "Ref Des/Silkscreen Bottom")
		(1 "F.Mask" user "Board Geometry/Soldermask Top")
		(3 "B.Mask" user "Board Geometry/Soldermask Bottom")
		(17 "Dwgs.User" user "User.Drawings")
		(19 "Cmts.User" user "User.Comments")
		(21 "Eco1.User" user "User.Eco1")
		(23 "Eco2.User" user "User.Eco2")
		(25 "Edge.Cuts" user "Board Geometry/Outline")
		(27 "Margin" user)
		(31 "F.CrtYd" user "Package Geometry/Place Bound Top")
		(29 "B.CrtYd" user "Package Geometry/Place Bound Bottom")
		(35 "F.Fab" user "Ref Des/Assembly Top")
		(33 "B.Fab" user "Ref Des/Assembly Bottom")
	)
	(footprint ""
		(layer "F.Cu")
		(at 77.0001 -3.50012)
		(property "Reference" "H5"
			(at 0 0 0)
			(layer "F.SilkS")
			(hide yes)
			(effects
				(font
					(size 1.27 1.27)
				)
			)
		)
		(property "Value" "HOLET217B237R130-GP"
			(at -5.08 -0.4572 0)
			(unlocked yes)
			(layer "F.Fab")
			(hide yes)
			(effects
				(font
					(size 1.016 1.016)
					(thickness 0.1524)
				)
			)
		)
		(property "Device Type" "HOLET217B237R130"
			(at -5.08 -1.9812 0)
			(unlocked yes)
			(layer "F.Fab")
			(hide yes)
			(effects
				(font
					(size 1.016 1.016)
					(thickness 0.1524)
				)
			)
		)
		(duplicate_pad_numbers_are_jumpers no)
		(fp_poly
			(pts
				(arc
					(start 3.3147 0)
					(mid -3.3147 0)
					(end 3.3147 0)
				)
			)
			(stroke
				(width 0)
				(type default)
			)
			(fill no)
			(layer "B.CrtYd")
		)
		(fp_poly
			(pts
				(arc
					(start 3.0607 0)
					(mid -3.0607 0)
					(end 3.0607 0)
				)
			)
			(stroke
				(width 0)
				(type default)
			)
			(fill no)
			(layer "F.CrtYd")
		)
		(fp_poly
			(pts
				(arc
					(start 3.3147 0)
					(mid -3.3147 0)
					(end 3.3147 0)
				)
			)
			(stroke
				(width 0)
				(type default)
			)
			(fill no)
			(layer "B.Fab")
		)
		(fp_poly
			(pts
				(arc
					(start 3.0607 0)
					(mid -3.0607 0)
					(end 3.0607 0)
				)
			)
			(stroke
				(width 0)
				(type default)
			)
			(fill no)
			(layer "F.Fab")
		)
		(pad "1" thru_hole circle
			(at 0 0)
			(size 5.5118 5.5118)
			(drill 3.302)
			(layers "*.Cu" "*.Mask")
			(remove_unused_layers no)
			(net "GND")
			(clearance -0.5969)
			(thermal_gap 0.3048)
			(padstack
				(mode front_inner_back)
				(layer "Inner"
					(shape circle)
					(size 3.7084 3.7084)
					(clearance 0.3048)
				)
				(layer "B.Cu"
					(shape circle)
					(size 6.0198 6.0198)
					(clearance -0.8509)
				)
			)
		)
	)
	(footprint ""
		(layer "F.Cu")
		(at 55.78602 -20.158456 -90)
		(property "Reference" "C21"
			(at 0 0 270)
			(layer "F.SilkS")
			(hide yes)
			(effects
				(font
					(size 1.27 1.27)
				)
			)
		)
		(property "Value" "SCD1U25V2KX-GP"
			(at 1.1811 -2.7051 270)
			(unlocked yes)
			(layer "F.Fab")
			(hide yes)
			(effects
				(font
					(size 1.016 1.016)
					(thickness 0.1524)
				)
			)
		)
		(property "Device Type" "C402H22"
			(at 1.1811 -4.2291 270)
			(unlocked yes)
			(layer "F.Fab")
			(hide yes)
			(effects
				(font
					(size 1.016 1.016)
					(thickness 0.1524)
				)
			)
		)
		(duplicate_pad_numbers_are_jumpers no)
		(fp_rect
			(start -0.4318 0.9525)
			(end 0.4318 -0.9525)
			(stroke
				(width 0)
				(type default)
			)
			(fill no)
			(layer "F.CrtYd")
		)
		(fp_rect
			(start -0.4318 0.9525)
			(end 0.4318 -0.9525)
			(stroke
				(width 0)
				(type default)
			)
			(fill no)
			(layer "F.Fab")
		)
		(pad "1" smd custom
			(at 0 -0.4445 270)
			(size 0.1524 0.1524)
			(layers "F.Cu" "F.Mask" "F.Paste")
			(net "P12V_SW_L")
			(options
				(clearance outline)
				(anchor circle)
			)
			(primitives
				(gr_poly
					(pts
						(arc
							(start 0.3048 -0.2032)
							(mid 0.275042 -0.275042)
							(end 0.2032 -0.3048)
						)
						(arc
							(start -0.2032 -0.3048)
							(mid -0.275042 -0.275042)
							(end -0.3048 -0.2032)
						)
						(arc
							(start -0.3048 0.2032)
							(mid -0.275042 0.275042)
							(end -0.2032 0.3048)
						)
						(arc
							(start 0.2032 0.3048)
							(mid 0.275042 0.275042)
							(end 0.3048 0.2032)
						)
					)
					(width 0)
					(fill yes)
				)
			)
		)
		(pad "2" smd custom
			(at 0 0.4445 270)
			(size 0.1524 0.1524)
			(layers "F.Cu" "F.Mask" "F.Paste")
			(net "GND")
			(options
				(clearance outline)
				(anchor circle)
			)
			(primitives
				(gr_poly
					(pts
						(arc
							(start 0.3048 -0.2032)
							(mid 0.275042 -0.275042)
							(end 0.2032 -0.3048)
						)
						(arc
							(start -0.2032 -0.3048)
							(mid -0.275042 -0.275042)
							(end -0.3048 -0.2032)
						)
						(arc
							(start -0.3048 0.2032)
							(mid -0.275042 0.275042)
							(end -0.2032 0.3048)
						)
						(arc
							(start 0.2032 0.3048)
							(mid 0.275042 0.275042)
							(end 0.3048 0.2032)
						)
					)
					(width 0)
					(fill yes)
				)
			)
		)
	)
	(footprint ""
		(layer "F.Cu")
		(at 85.852 -5.08 90)
		(property "Reference" "R147"
			(at 0 0 90)
			(layer "F.SilkS")
			(hide yes)
			(effects
				(font
					(size 1.27 1.27)
				)
			)
		)
		(property "Value" "4K7R2J-2-GP"
			(at 0.064008 -3.993896 90)
			(unlocked yes)
			(layer "F.Fab")
			(hide yes)
			(effects
				(font
					(size 1.016 1.016)
					(thickness 0.1524)
				)
			)
		)
		(property "Device Type" "R402H16"
			(at 0.064008 -5.517896 90)
			(unlocked yes)
			(layer "F.Fab")
			(hide yes)
			(effects
				(font
					(size 1.016 1.016)
					(thickness 0.1524)
				)
			)
		)
		(duplicate_pad_numbers_are_jumpers no)
		(fp_line
			(start 0.508 -0.9398)
			(end -0.508 -0.9398)
			(stroke
				(width 0.1524)
				(type default)
			)
			(layer "F.SilkS")
		)
		(fp_line
			(start -0.508 -0.9398)
			(end -0.508 0.9398)
			(stroke
				(width 0.1524)
				(type default)
			)
			(layer "F.SilkS")
		)
		(fp_rect
			(start -0.508 0.9398)
			(end 0.508 -0.9398)
			(stroke
				(width 0)
				(type default)
			)
			(fill no)
			(layer "F.CrtYd")
		)
		(fp_rect
			(start -0.508 0.9398)
			(end 0.508 -0.9398)
			(stroke
				(width 0)
				(type default)
			)
			(fill no)
			(layer "F.Fab")
		)
		(pad "1" smd custom
			(at 0 -0.4445 90)
			(size 0.1397 0.1397)
			(layers "F.Cu" "F.Mask" "F.Paste")
			(net "P3V3")
			(options
				(clearance outline)
				(anchor circle)
			)
			(primitives
				(gr_poly
					(pts
						(arc
							(start -0.1778 -0.2794)
							(mid -0.249642 -0.249642)
							(end -0.2794 -0.1778)
						)
						(arc
							(start -0.2794 0.1778)
							(mid -0.249642 0.249642)
							(end -0.1778 0.2794)
						)
						(arc
							(start 0.1778 0.2794)
							(mid 0.249642 0.249642)
							(end 0.2794 0.1778)
						)
						(arc
							(start 0.2794 -0.1778)
							(mid 0.249642 -0.249642)
							(end 0.1778 -0.2794)
						)
					)
					(width 0)
					(fill yes)
				)
			)
		)
		(pad "2" smd custom
			(at 0 0.4445 90)
			(size 0.1397 0.1397)
			(layers "F.Cu" "F.Mask" "F.Paste")
			(net "PWR_EN_D_2")
			(options
				(clearance outline)
				(anchor circle)
			)
			(primitives
				(gr_poly
					(pts
						(arc
							(start -0.1778 -0.2794)
							(mid -0.249642 -0.249642)
							(end -0.2794 -0.1778)
						)
						(arc
							(start -0.2794 0.1778)
							(mid -0.249642 0.249642)
							(end -0.1778 0.2794)
						)
						(arc
							(start 0.1778 0.2794)
							(mid 0.249642 0.249642)
							(end 0.2794 0.1778)
						)
						(arc
							(start 0.2794 -0.1778)
							(mid 0.249642 -0.249642)
							(end 0.1778 -0.2794)
						)
					)
					(width 0)
					(fill yes)
				)
			)
		)
	)
	(footprint ""
		(layer "F.Cu")
		(at 81.520284 -11.335766 180)
		(property "Reference" "PC2"
			(at 0 0 180)
			(layer "F.SilkS")
			(hide yes)
			(effects
				(font
					(size 1.27 1.27)
				)
			)
		)
		(property "Value" "SCD1U25V2KX-GP"
			(at 1.1811 -2.7051 180)
			(unlocked yes)
			(layer "F.Fab")
			(hide yes)
			(effects
				(font
					(size 1.016 1.016)
					(thickness 0.1524)
				)
			)
		)
		(property "Device Type" "C402H22"
			(at 1.1811 -4.2291 180)
			(unlocked yes)
			(layer "F.Fab")
			(hide yes)
			(effects
				(font
					(size 1.016 1.016)
					(thickness 0.1524)
				)
			)
		)
		(duplicate_pad_numbers_are_jumpers no)
		(fp_rect
			(start -0.4318 0.9525)
			(end 0.4318 -0.9525)
			(stroke
				(width 0)
				(type default)
			)
			(fill no)
			(layer "F.CrtYd")
		)
		(fp_rect
			(start -0.4318 0.9525)
			(end 0.4318 -0.9525)
			(stroke
				(width 0)
				(type default)
			)
			(fill no)
			(layer "F.Fab")
		)
		(pad "1" smd custom
			(at 0 -0.4445 180)
			(size 0.1524 0.1524)
			(layers "F.Cu" "F.Mask" "F.Paste")
			(net "P3V3")
			(options
				(clearance outline)
				(anchor circle)
			)
			(primitives
				(gr_poly
					(pts
						(arc
							(start 0.3048 -0.2032)
							(mid 0.275042 -0.275042)
							(end 0.2032 -0.3048)
						)
						(arc
							(start -0.2032 -0.3048)
							(mid -0.275042 -0.275042)
							(end -0.3048 -0.2032)
						)
						(arc
							(start -0.3048 0.2032)
							(mid -0.275042 0.275042)
							(end -0.2032 0.3048)
						)
						(arc
							(start 0.2032 0.3048)
							(mid 0.275042 0.275042)
							(end 0.3048 0.2032)
						)
					)
					(width 0)
					(fill yes)
				)
			)
		)
		(pad "2" smd custom
			(at 0 0.4445 180)
			(size 0.1524 0.1524)
			(layers "F.Cu" "F.Mask" "F.Paste")
			(net "GND")
			(options
				(clearance outline)
				(anchor circle)
			)
			(primitives
				(gr_poly
					(pts
						(arc
							(start 0.3048 -0.2032)
							(mid 0.275042 -0.275042)
							(end 0.2032 -0.3048)
						)
						(arc
							(start -0.2032 -0.3048)
							(mid -0.275042 -0.275042)
							(end -0.3048 -0.2032)
						)
						(arc
							(start -0.3048 0.2032)
							(mid -0.275042 0.275042)
							(end -0.2032 0.3048)
						)
						(arc
							(start 0.2032 0.3048)
							(mid 0.275042 0.275042)
							(end 0.3048 0.2032)
						)
					)
					(width 0)
					(fill yes)
				)
			)
		)
	)
	(footprint ""
		(layer "F.Cu")
		(at 75.0062 -38.1 -90)
		(property "Reference" "C8"
			(at 0 0 270)
			(layer "F.SilkS")
			(hide yes)
			(effects
				(font
					(size 1.27 1.27)
				)
			)
		)
		(property "Value" "SC10U25V6KX-1GP"
			(at -0.0762 -5.1308 270)
			(unlocked yes)
			(layer "F.Fab")
			(hide yes)
			(effects
				(font
					(size 1.016 1.016)
					(thickness 0.1524)
				)
			)
		)
		(property "Device Type" "C1206H71"
			(at -0.127 -6.6548 270)
			(unlocked yes)
			(layer "F.Fab")
			(hide yes)
			(effects
				(font
					(size 1.016 1.016)
					(thickness 0.1524)
				)
			)
		)
		(duplicate_pad_numbers_are_jumpers no)
		(fp_line
			(start -1.016 2.2352)
			(end -1.016 0.8382)
			(stroke
				(width 0.1524)
				(type default)
			)
			(layer "F.SilkS")
		)
		(fp_line
			(start 1.016 2.2352)
			(end -1.016 2.2352)
			(stroke
				(width 0.1524)
				(type default)
			)
			(layer "F.SilkS")
		)
		(fp_line
			(start 1.016 0.8382)
			(end 1.016 2.2352)
			(stroke
				(width 0.1524)
				(type default)
			)
			(layer "F.SilkS")
		)
		(fp_line
			(start -1.016 -0.8382)
			(end -1.016 -2.2352)
			(stroke
				(width 0.1524)
				(type default)
			)
			(layer "F.SilkS")
		)
		(fp_line
			(start -1.016 -2.2352)
			(end 1.016 -2.2352)
			(stroke
				(width 0.1524)
				(type default)
			)
			(layer "F.SilkS")
		)
		(fp_line
			(start 1.016 -2.2352)
			(end 1.016 -0.8382)
			(stroke
				(width 0.1524)
				(type default)
			)
			(layer "F.SilkS")
		)
		(fp_rect
			(start -1.0922 2.3114)
			(end 1.0922 -2.3114)
			(stroke
				(width 0)
				(type default)
			)
			(fill no)
			(layer "F.CrtYd")
		)
		(fp_poly
			(pts
				(xy 1.0922 -2.3114) (xy 1.0922 2.3114) (xy -1.0922 2.3114) (xy -1.0922 -2.3114)
			)
			(stroke
				(width 0)
				(type default)
			)
			(fill no)
			(layer "F.Fab")
		)
		(pad "1" smd rect
			(at 0 -1.397 270)
			(size 1.651 1.27)
			(layers "F.Cu" "F.Mask" "F.Paste")
			(net "P12V_SW_R")
		)
		(pad "2" smd rect
			(at 0 1.397 270)
			(size 1.651 1.27)
			(layers "F.Cu" "F.Mask" "F.Paste")
			(net "GND")
		)
	)
)
